(kicad_pcb
	(version 20260206)
	(generator "pcbnew")
	(generator_version "10.0")
	(general
		(thickness 1.6)
		(legacy_teardrops no)
	)
	(paper "A4")
	(title_block
		(title "04192023_DAF0TMB3IC0_F0TG_MB_C_brd_V02_OCP.brd")
		(comment 1 "Grand Teton / footprints 5105-5111 of 8354")
	)
	(layers
		(0 "F.Cu" signal "TOP")
		(4 "In1.Cu" signal "GND")
		(6 "In2.Cu" signal "IN1")
		(8 "In3.Cu" signal "GND1")
		(10 "In4.Cu" signal "IN2")
		(12 "In5.Cu" signal "GND2")
		(14 "In6.Cu" signal "IN3")
		(16 "In7.Cu" signal "GND3")
		(18 "In8.Cu" signal "VCC")
		(20 "In9.Cu" signal "VCC1")
		(22 "In10.Cu" signal "GND4")
		(24 "In11.Cu" signal "IN4")
		(26 "In12.Cu" signal "GND5")
		(28 "In13.Cu" signal "IN5")
		(30 "In14.Cu" signal "GND6")
		(32 "In15.Cu" signal "IN6")
		(34 "In16.Cu" signal "GND7")
		(2 "B.Cu" signal "BOTTOM")
		(9 "F.Adhes" user "F.Adhesive")
		(11 "B.Adhes" user "B.Adhesive")
		(13 "F.Paste" user "Package Geometry/Pastemask Top")
		(15 "B.Paste" user "Package Geometry/Pastemask Bottom")
		(5 "F.SilkS" user "Ref Des/Silkscreen Top")
		(7 "B.SilkS" user "Ref Des/Silkscreen Bottom")
		(1 "F.Mask" user "Board Geometry/Soldermask Top")
		(3 "B.Mask" user "Board Geometry/Soldermask Bottom")
		(17 "Dwgs.User" user "User.Drawings")
		(19 "Cmts.User" user "User.Comments")
		(21 "Eco1.User" user "User.Eco1")
		(23 "Eco2.User" user "User.Eco2")
		(25 "Edge.Cuts" user "Board Geometry/Outline")
		(27 "Margin" user)
		(31 "F.CrtYd" user "Package Geometry/Place Bound Top")
		(29 "B.CrtYd" user "Package Geometry/Place Bound Bottom")
		(35 "F.Fab" user "Ref Des/Assembly Top")
		(33 "B.Fab" user "Ref Des/Assembly Bottom")
	)
	(footprint ""
		(layer "B.Cu")
		(at 123.611386 -249.368564)
		(property "Reference" "C2320"
			(at 0 0 0)
			(layer "B.SilkS")
			(hide yes)
			(effects
				(font
					(size 1.27 1.27)
				)
				(justify mirror)
			)
		)
		(property "Value" ""
			(at 0 0 0)
			(layer "B.Fab")
			(effects
				(font
					(size 1.27 1.27)
				)
				(justify mirror)
			)
		)
		(duplicate_pad_numbers_are_jumpers no)
		(fp_line
			(start -0.7874 -0.4064)
			(end -0.7874 0.4064)
			(stroke
				(width 0.1524)
				(type default)
			)
			(layer "B.SilkS")
		)
		(fp_line
			(start -0.7874 0.4064)
			(end 0.7874 0.4064)
			(stroke
				(width 0.1524)
				(type default)
			)
			(layer "B.SilkS")
		)
		(fp_line
			(start 0.7874 -0.4064)
			(end -0.7874 -0.4064)
			(stroke
				(width 0.1524)
				(type default)
			)
			(layer "B.SilkS")
		)
		(fp_line
			(start 0.7874 0.4064)
			(end 0.7874 -0.4064)
			(stroke
				(width 0.1524)
				(type default)
			)
			(layer "B.SilkS")
		)
		(fp_line
			(start -0.67945 -0.3048)
			(end -0.67945 0.3048)
			(stroke
				(width 0.1)
				(type default)
			)
			(layer "B.Fab")
		)
		(fp_line
			(start -0.67945 0.3048)
			(end -0.120396 0.3048)
			(stroke
				(width 0.1)
				(type default)
			)
			(layer "B.Fab")
		)
		(fp_line
			(start -0.12065 -0.3048)
			(end -0.67945 -0.3048)
			(stroke
				(width 0.1)
				(type default)
			)
			(layer "B.Fab")
		)
		(fp_line
			(start -0.12065 -0.2794)
			(end -0.12065 -0.3048)
			(stroke
				(width 0.1)
				(type default)
			)
			(layer "B.Fab")
		)
		(fp_line
			(start -0.120396 0.2794)
			(end 0.12065 0.2794)
			(stroke
				(width 0.1)
				(type default)
			)
			(layer "B.Fab")
		)
		(fp_line
			(start -0.120396 0.3048)
			(end -0.120396 0.2794)
			(stroke
				(width 0.1)
				(type default)
			)
			(layer "B.Fab")
		)
		(fp_line
			(start 0.12065 -0.305054)
			(end 0.12065 -0.2794)
			(stroke
				(width 0.1)
				(type default)
			)
			(layer "B.Fab")
		)
		(fp_line
			(start 0.12065 -0.2794)
			(end -0.12065 -0.2794)
			(stroke
				(width 0.1)
				(type default)
			)
			(layer "B.Fab")
		)
		(fp_line
			(start 0.12065 0.2794)
			(end 0.12065 0.3048)
			(stroke
				(width 0.1)
				(type default)
			)
			(layer "B.Fab")
		)
		(fp_line
			(start 0.12065 0.3048)
			(end 0.67945 0.3048)
			(stroke
				(width 0.1)
				(type default)
			)
			(layer "B.Fab")
		)
		(fp_line
			(start 0.67945 -0.305054)
			(end 0.12065 -0.305054)
			(stroke
				(width 0.1)
				(type default)
			)
			(layer "B.Fab")
		)
		(fp_line
			(start 0.67945 0.3048)
			(end 0.67945 -0.305054)
			(stroke
				(width 0.1)
				(type default)
			)
			(layer "B.Fab")
		)
		(pad "1" smd circle
			(at 0.40005 0 180)
			(size 0 0)
			(layers "B.Cu" "B.Mask" "B.Paste")
			(net "PVDDCR_CPU0_P1")
		)
		(pad "2" smd circle
			(at -0.40005 0 180)
			(size 0 0)
			(layers "B.Cu" "B.Mask" "B.Paste")
			(net "GND")
		)
	)
	(footprint ""
		(layer "B.Cu")
		(at 12.025376 -134.189216 180)
		(property "Reference" "C1889"
			(at 0 0 0)
			(layer "B.SilkS")
			(hide yes)
			(effects
				(font
					(size 1.27 1.27)
				)
				(justify mirror)
			)
		)
		(property "Value" ""
			(at 0 0 0)
			(layer "B.Fab")
			(effects
				(font
					(size 1.27 1.27)
				)
				(justify mirror)
			)
		)
		(duplicate_pad_numbers_are_jumpers no)
		(fp_line
			(start 0.7874 0.4064)
			(end 0.7874 -0.4064)
			(stroke
				(width 0.1524)
				(type default)
			)
			(layer "B.SilkS")
		)
		(fp_line
			(start 0.7874 -0.4064)
			(end -0.7874 -0.4064)
			(stroke
				(width 0.1524)
				(type default)
			)
			(layer "B.SilkS")
		)
		(fp_line
			(start -0.7874 0.4064)
			(end 0.7874 0.4064)
			(stroke
				(width 0.1524)
				(type default)
			)
			(layer "B.SilkS")
		)
		(fp_line
			(start -0.7874 -0.4064)
			(end -0.7874 0.4064)
			(stroke
				(width 0.1524)
				(type default)
			)
			(layer "B.SilkS")
		)
		(fp_line
			(start 0.67945 0.3048)
			(end 0.67945 -0.305054)
			(stroke
				(width 0.1)
				(type default)
			)
			(layer "B.Fab")
		)
		(fp_line
			(start 0.67945 -0.305054)
			(end 0.12065 -0.305054)
			(stroke
				(width 0.1)
				(type default)
			)
			(layer "B.Fab")
		)
		(fp_line
			(start 0.12065 0.3048)
			(end 0.67945 0.3048)
			(stroke
				(width 0.1)
				(type default)
			)
			(layer "B.Fab")
		)
		(fp_line
			(start 0.12065 0.2794)
			(end 0.12065 0.3048)
			(stroke
				(width 0.1)
				(type default)
			)
			(layer "B.Fab")
		)
		(fp_line
			(start 0.12065 -0.2794)
			(end -0.12065 -0.2794)
			(stroke
				(width 0.1)
				(type default)
			)
			(layer "B.Fab")
		)
		(fp_line
			(start 0.12065 -0.305054)
			(end 0.12065 -0.2794)
			(stroke
				(width 0.1)
				(type default)
			)
			(layer "B.Fab")
		)
		(fp_line
			(start -0.120396 0.3048)
			(end -0.120396 0.2794)
			(stroke
				(width 0.1)
				(type default)
			)
			(layer "B.Fab")
		)
		(fp_line
			(start -0.120396 0.2794)
			(end 0.12065 0.2794)
			(stroke
				(width 0.1)
				(type default)
			)
			(layer "B.Fab")
		)
		(fp_line
			(start -0.12065 -0.2794)
			(end -0.12065 -0.3048)
			(stroke
				(width 0.1)
				(type default)
			)
			(layer "B.Fab")
		)
		(fp_line
			(start -0.12065 -0.3048)
			(end -0.67945 -0.3048)
			(stroke
				(width 0.1)
				(type default)
			)
			(layer "B.Fab")
		)
		(fp_line
			(start -0.67945 0.3048)
			(end -0.120396 0.3048)
			(stroke
				(width 0.1)
				(type default)
			)
			(layer "B.Fab")
		)
		(fp_line
			(start -0.67945 -0.3048)
			(end -0.67945 0.3048)
			(stroke
				(width 0.1)
				(type default)
			)
			(layer "B.Fab")
		)
		(pad "1" smd circle
			(at 0.40005 0)
			(size 0 0)
			(layers "B.Cu" "B.Mask" "B.Paste")
			(net "VFG3P3_CLK_GEN")
		)
		(pad "2" smd circle
			(at -0.40005 0)
			(size 0 0)
			(layers "B.Cu" "B.Mask" "B.Paste")
			(net "GND")
		)
	)
	(footprint ""
		(layer "B.Cu")
		(at 350.723454 -269.30731)
		(property "Reference" "C2210"
			(at 0 0 0)
			(layer "B.SilkS")
			(hide yes)
			(effects
				(font
					(size 1.27 1.27)
				)
				(justify mirror)
			)
		)
		(property "Value" ""
			(at 0 0 0)
			(layer "B.Fab")
			(effects
				(font
					(size 1.27 1.27)
				)
				(justify mirror)
			)
		)
		(duplicate_pad_numbers_are_jumpers no)
		(fp_line
			(start -0.7874 -0.4064)
			(end -0.7874 0.4064)
			(stroke
				(width 0.1524)
				(type default)
			)
			(layer "B.SilkS")
		)
		(fp_line
			(start -0.7874 0.4064)
			(end 0.7874 0.4064)
			(stroke
				(width 0.1524)
				(type default)
			)
			(layer "B.SilkS")
		)
		(fp_line
			(start 0.7874 -0.4064)
			(end -0.7874 -0.4064)
			(stroke
				(width 0.1524)
				(type default)
			)
			(layer "B.SilkS")
		)
		(fp_line
			(start 0.7874 0.4064)
			(end 0.7874 -0.4064)
			(stroke
				(width 0.1524)
				(type default)
			)
			(layer "B.SilkS")
		)
		(fp_line
			(start -0.67945 -0.3048)
			(end -0.67945 0.3048)
			(stroke
				(width 0.1)
				(type default)
			)
			(layer "B.Fab")
		)
		(fp_line
			(start -0.67945 0.3048)
			(end -0.120396 0.3048)
			(stroke
				(width 0.1)
				(type default)
			)
			(layer "B.Fab")
		)
		(fp_line
			(start -0.12065 -0.3048)
			(end -0.67945 -0.3048)
			(stroke
				(width 0.1)
				(type default)
			)
			(layer "B.Fab")
		)
		(fp_line
			(start -0.12065 -0.2794)
			(end -0.12065 -0.3048)
			(stroke
				(width 0.1)
				(type default)
			)
			(layer "B.Fab")
		)
		(fp_line
			(start -0.120396 0.2794)
			(end 0.12065 0.2794)
			(stroke
				(width 0.1)
				(type default)
			)
			(layer "B.Fab")
		)
		(fp_line
			(start -0.120396 0.3048)
			(end -0.120396 0.2794)
			(stroke
				(width 0.1)
				(type default)
			)
			(layer "B.Fab")
		)
		(fp_line
			(start 0.12065 -0.305054)
			(end 0.12065 -0.2794)
			(stroke
				(width 0.1)
				(type default)
			)
			(layer "B.Fab")
		)
		(fp_line
			(start 0.12065 -0.2794)
			(end -0.12065 -0.2794)
			(stroke
				(width 0.1)
				(type default)
			)
			(layer "B.Fab")
		)
		(fp_line
			(start 0.12065 0.2794)
			(end 0.12065 0.3048)
			(stroke
				(width 0.1)
				(type default)
			)
			(layer "B.Fab")
		)
		(fp_line
			(start 0.12065 0.3048)
			(end 0.67945 0.3048)
			(stroke
				(width 0.1)
				(type default)
			)
			(layer "B.Fab")
		)
		(fp_line
			(start 0.67945 -0.305054)
			(end 0.12065 -0.305054)
			(stroke
				(width 0.1)
				(type default)
			)
			(layer "B.Fab")
		)
		(fp_line
			(start 0.67945 0.3048)
			(end 0.67945 -0.305054)
			(stroke
				(width 0.1)
				(type default)
			)
			(layer "B.Fab")
		)
		(pad "1" smd circle
			(at 0.40005 0 180)
			(size 0 0)
			(layers "B.Cu" "B.Mask" "B.Paste")
			(net "PVDDCR_CPU1_P0")
		)
		(pad "2" smd circle
			(at -0.40005 0 180)
			(size 0 0)
			(layers "B.Cu" "B.Mask" "B.Paste")
			(net "GND")
		)
	)
	(footprint ""
		(layer "B.Cu")
		(at 24.939244 -349.386398 -90)
		(property "Reference" "PR375"
			(at 0 0 90)
			(layer "B.SilkS")
			(hide yes)
			(effects
				(font
					(size 1.27 1.27)
				)
				(justify mirror)
			)
		)
		(property "Value" ""
			(at 0 0 90)
			(layer "B.Fab")
			(effects
				(font
					(size 1.27 1.27)
				)
				(justify mirror)
			)
		)
		(duplicate_pad_numbers_are_jumpers no)
		(fp_line
			(start -0.7874 0.4064)
			(end 0.7874 0.4064)
			(stroke
				(width 0.1524)
				(type default)
			)
			(layer "B.SilkS")
		)
		(fp_line
			(start 0.7874 0.4064)
			(end 0.7874 -0.4064)
			(stroke
				(width 0.1524)
				(type default)
			)
			(layer "B.SilkS")
		)
		(fp_line
			(start -0.7874 -0.4064)
			(end -0.7874 0.4064)
			(stroke
				(width 0.1524)
				(type default)
			)
			(layer "B.SilkS")
		)
		(fp_line
			(start 0.7874 -0.4064)
			(end -0.7874 -0.4064)
			(stroke
				(width 0.1524)
				(type default)
			)
			(layer "B.SilkS")
		)
		(fp_line
			(start -0.67945 0.3048)
			(end -0.120396 0.3048)
			(stroke
				(width 0.1)
				(type default)
			)
			(layer "B.Fab")
		)
		(fp_line
			(start -0.120396 0.3048)
			(end -0.120396 0.2794)
			(stroke
				(width 0.1)
				(type default)
			)
			(layer "B.Fab")
		)
		(fp_line
			(start 0.12065 0.3048)
			(end 0.67945 0.3048)
			(stroke
				(width 0.1)
				(type default)
			)
			(layer "B.Fab")
		)
		(fp_line
			(start 0.67945 0.3048)
			(end 0.67945 -0.305054)
			(stroke
				(width 0.1)
				(type default)
			)
			(layer "B.Fab")
		)
		(fp_line
			(start -0.120396 0.2794)
			(end 0.12065 0.2794)
			(stroke
				(width 0.1)
				(type default)
			)
			(layer "B.Fab")
		)
		(fp_line
			(start 0.12065 0.2794)
			(end 0.12065 0.3048)
			(stroke
				(width 0.1)
				(type default)
			)
			(layer "B.Fab")
		)
		(fp_line
			(start -0.12065 -0.2794)
			(end -0.12065 -0.3048)
			(stroke
				(width 0.1)
				(type default)
			)
			(layer "B.Fab")
		)
		(fp_line
			(start 0.12065 -0.2794)
			(end -0.12065 -0.2794)
			(stroke
				(width 0.1)
				(type default)
			)
			(layer "B.Fab")
		)
		(fp_line
			(start -0.67945 -0.3048)
			(end -0.67945 0.3048)
			(stroke
				(width 0.1)
				(type default)
			)
			(layer "B.Fab")
		)
		(fp_line
			(start -0.12065 -0.3048)
			(end -0.67945 -0.3048)
			(stroke
				(width 0.1)
				(type default)
			)
			(layer "B.Fab")
		)
		(fp_line
			(start 0.12065 -0.305054)
			(end 0.12065 -0.2794)
			(stroke
				(width 0.1)
				(type default)
			)
			(layer "B.Fab")
		)
		(fp_line
			(start 0.67945 -0.305054)
			(end 0.12065 -0.305054)
			(stroke
				(width 0.1)
				(type default)
			)
			(layer "B.Fab")
		)
		(pad "1" smd circle
			(at 0.40005 0 90)
			(size 0 0)
			(layers "B.Cu" "B.Mask" "B.Paste")
			(net "PVDDIO_P1_VOS4")
		)
		(pad "2" smd circle
			(at -0.40005 0 90)
			(size 0 0)
			(layers "B.Cu" "B.Mask" "B.Paste")
			(net "PVDDIO_P1")
		)
	)
	(footprint ""
		(layer "B.Cu")
		(at 412.0642 -172.407072 90)
		(property "Reference" "PC614_3"
			(at 0 0 90)
			(layer "B.SilkS")
			(hide yes)
			(effects
				(font
					(size 1.27 1.27)
				)
				(justify mirror)
			)
		)
		(property "Value" ""
			(at 0 0 90)
			(layer "B.Fab")
			(effects
				(font
					(size 1.27 1.27)
				)
				(justify mirror)
			)
		)
		(duplicate_pad_numbers_are_jumpers no)
		(fp_line
			(start 1.524 -0.762)
			(end -1.524 -0.762)
			(stroke
				(width 0.1524)
				(type default)
			)
			(layer "B.SilkS")
		)
		(fp_line
			(start -1.524 -0.762)
			(end -1.524 0.762)
			(stroke
				(width 0.1524)
				(type default)
			)
			(layer "B.SilkS")
		)
		(fp_line
			(start 1.524 0.762)
			(end 1.524 -0.762)
			(stroke
				(width 0.1524)
				(type default)
			)
			(layer "B.SilkS")
		)
		(fp_line
			(start -1.524 0.762)
			(end 1.524 0.762)
			(stroke
				(width 0.1524)
				(type default)
			)
			(layer "B.SilkS")
		)
		(fp_line
			(start 1.1049 -0.724916)
			(end 1.1049 0.724916)
			(stroke
				(width 0.1)
				(type default)
			)
			(layer "B.Fab")
		)
		(fp_line
			(start -1.1049 -0.724916)
			(end 1.1049 -0.724916)
			(stroke
				(width 0.1)
				(type default)
			)
			(layer "B.Fab")
		)
		(fp_line
			(start 1.1049 0.724916)
			(end -1.1049 0.724916)
			(stroke
				(width 0.1)
				(type default)
			)
			(layer "B.Fab")
		)
		(fp_line
			(start -1.1049 0.724916)
			(end -1.1049 -0.724916)
			(stroke
				(width 0.1)
				(type default)
			)
			(layer "B.Fab")
		)
		(pad "1" smd rect
			(at 0.889 0 90)
			(size 1.016 1.27)
			(layers "B.Cu" "B.Mask" "B.Paste")
			(net "PVDDCR_SOC_P0")
		)
		(pad "2" smd rect
			(at -0.889 0 90)
			(size 1.016 1.27)
			(layers "B.Cu" "B.Mask" "B.Paste")
			(net "GND")
		)
	)
	(footprint ""
		(layer "B.Cu")
		(at 367.975388 -175.106076 90)
		(property "Reference" "PR324"
			(at 0 0 90)
			(layer "B.SilkS")
			(hide yes)
			(effects
				(font
					(size 1.27 1.27)
				)
				(justify mirror)
			)
		)
		(property "Value" ""
			(at 0 0 90)
			(layer "B.Fab")
			(effects
				(font
					(size 1.27 1.27)
				)
				(justify mirror)
			)
		)
		(duplicate_pad_numbers_are_jumpers no)
		(fp_line
			(start 0.7874 -0.4064)
			(end -0.7874 -0.4064)
			(stroke
				(width 0.1524)
				(type default)
			)
			(layer "B.SilkS")
		)
		(fp_line
			(start -0.7874 -0.4064)
			(end -0.7874 0.4064)
			(stroke
				(width 0.1524)
				(type default)
			)
			(layer "B.SilkS")
		)
		(fp_line
			(start 0.7874 0.4064)
			(end 0.7874 -0.4064)
			(stroke
				(width 0.1524)
				(type default)
			)
			(layer "B.SilkS")
		)
		(fp_line
			(start -0.7874 0.4064)
			(end 0.7874 0.4064)
			(stroke
				(width 0.1524)
				(type default)
			)
			(layer "B.SilkS")
		)
		(fp_line
			(start 0.67945 -0.305054)
			(end 0.12065 -0.305054)
			(stroke
				(width 0.1)
				(type default)
			)
			(layer "B.Fab")
		)
		(fp_line
			(start 0.12065 -0.305054)
			(end 0.12065 -0.2794)
			(stroke
				(width 0.1)
				(type default)
			)
			(layer "B.Fab")
		)
		(fp_line
			(start -0.12065 -0.3048)
			(end -0.67945 -0.3048)
			(stroke
				(width 0.1)
				(type default)
			)
			(layer "B.Fab")
		)
		(fp_line
			(start -0.67945 -0.3048)
			(end -0.67945 0.3048)
			(stroke
				(width 0.1)
				(type default)
			)
			(layer "B.Fab")
		)
		(fp_line
			(start 0.12065 -0.2794)
			(end -0.12065 -0.2794)
			(stroke
				(width 0.1)
				(type default)
			)
			(layer "B.Fab")
		)
		(fp_line
			(start -0.12065 -0.2794)
			(end -0.12065 -0.3048)
			(stroke
				(width 0.1)
				(type default)
			)
			(layer "B.Fab")
		)
		(fp_line
			(start 0.12065 0.2794)
			(end 0.12065 0.3048)
			(stroke
				(width 0.1)
				(type default)
			)
			(layer "B.Fab")
		)
		(fp_line
			(start -0.120396 0.2794)
			(end 0.12065 0.2794)
			(stroke
				(width 0.1)
				(type default)
			)
			(layer "B.Fab")
		)
		(fp_line
			(start 0.67945 0.3048)
			(end 0.67945 -0.305054)
			(stroke
				(width 0.1)
				(type default)
			)
			(layer "B.Fab")
		)
		(fp_line
			(start 0.12065 0.3048)
			(end 0.67945 0.3048)
			(stroke
				(width 0.1)
				(type default)
			)
			(layer "B.Fab")
		)
		(fp_line
			(start -0.120396 0.3048)
			(end -0.120396 0.2794)
			(stroke
				(width 0.1)
				(type default)
			)
			(layer "B.Fab")
		)
		(fp_line
			(start -0.67945 0.3048)
			(end -0.120396 0.3048)
			(stroke
				(width 0.1)
				(type default)
			)
			(layer "B.Fab")
		)
		(pad "1" smd circle
			(at 0.40005 0 270)
			(size 0 0)
			(layers "B.Cu" "B.Mask" "B.Paste")
			(net "PVDDCR_CPU0_P0_VOS1")
		)
		(pad "2" smd circle
			(at -0.40005 0 270)
			(size 0 0)
			(layers "B.Cu" "B.Mask" "B.Paste")
			(net "PVDDCR_CPU0_P0")
		)
	)
	(footprint ""
		(layer "B.Cu")
		(at 355.111304 -395.148562 90)
		(property "Reference" "C653"
			(at 0 0 90)
			(layer "B.SilkS")
			(hide yes)
			(effects
				(font
					(size 1.27 1.27)
				)
				(justify mirror)
			)
		)
		(property "Value" ""
			(at 0 0 90)
			(layer "B.Fab")
			(effects
				(font
					(size 1.27 1.27)
				)
				(justify mirror)
			)
		)
		(duplicate_pad_numbers_are_jumpers no)
		(fp_line
			(start 0.299974 -0.150114)
			(end -0.299974 -0.150114)
			(stroke
				(width 0.1)
				(type default)
			)
			(layer "B.Fab")
		)
		(fp_line
			(start -0.299974 -0.150114)
			(end -0.299974 0.150114)
			(stroke
				(width 0.1)
				(type default)
			)
			(layer "B.Fab")
		)
		(fp_line
			(start 0.299974 0.150114)
			(end 0.299974 -0.150114)
			(stroke
				(width 0.1)
				(type default)
			)
			(layer "B.Fab")
		)
		(fp_line
			(start -0.299974 0.150114)
			(end 0.299974 0.150114)
			(stroke
				(width 0.1)
				(type default)
			)
			(layer "B.Fab")
		)
		(pad "1" smd rect
			(at 0.2667 0 270)
			(size 0.3048 0.381)
			(layers "B.Cu" "B.Mask" "B.Paste")
			(net "P0V9_CPU0_RT1_2A")
		)
		(pad "2" smd rect
			(at -0.2667 0 270)
			(size 0.3048 0.381)
			(layers "B.Cu" "B.Mask" "B.Paste")
			(net "GND")
		)
	)
)
